# HONEY BADGER DPB LOW LOSS HS(D)-1A BOM of 55.B0707.D07G.xlsx — HONEY BADGER DPB LOW LOSS HS(D) (bom)
| Level | Parent Number | Part Number | Description | Green Factor | Life Cycle State | Manufacturer | Manufacturer Part Number | Source | BOM Usage | M/P Code | S/D | Qty | UoM | Location |
| 1 | 55.B0707.D07G | 55.B0707.S07G | HONEY BADGER DPB LOW LOSS HS(S)-1A | N/A; | Released |  |  |  | E | Manufacture | DIP | 1 | PCS |  |
| 2 | 55.B0707.S07G | 020.F0274.0029 | CONN CTR SMD S14+P15 C20202-12933-L,LCP | R2_SA; | Released | ALLTOP | C20202-12933-L | Single |  | Purchase | SMT | 15 | PCS | SKT1 SKT10 SKT11 SKT12 SKT13 SKT14 SKT15 SKT2 SKT3 SKT4 SKT5 SKT6 SKT7 SKT8 SKT9 |
| 2 | 55.B0707.S07G | 083.55130.008F | DIODE S.B RB551V30 SOD-323 | R2_SA;HF_SA; | Released | YEASHIN | RB551V30 | Single |  | Purchase | SMT | 15 | PCS | D15 D16 D17 D18 D19 D20 D21 D23 D24 D25 D26 D27 D28 D29 D30 |
| 2 | 55.B0707.S07G | 20.C0093.164 | CONN EDGE SMD 164P G630HAA12246EU PCIE | R2_SA; | Released | AMPHENOL | G630HAA12246EU | Single |  | Purchase | SMT | 2 | PCS | CN1 CN2 |
| 2 | 55.B0707.S07G | 20.C0094.036 | CONN EDGE SMD 36P G630H3612246EU PCIE | R2_SA; | Released | AMPHENOL | G630H3612246EU | Single |  | Purchase | SMT | 4 | PCS | CN5 CN6 CN8 CN9 |
| 2 | 55.B0707.S07G | 20.F2288.060 | CONN CTR SMD 36P+24S GPCE54362413HR,PA4T | R2_SA; | Released | AMPHENOL | GPCE54362413HR | Single |  | Purchase | SMT | 1 | PCS | CN7 |
| 2 | 55.B0707.S07G | 48.B0744.01A | PCB 14545-1A HONEY BADGER LOW LOS 8L HAN | R2_C; | Released | HANNSTAR |  | Single |  | Purchase | SMT | 1 | PCS |  |
| 2 | 55.B0707.S07G | 63.00000.00L | CHIP RES 0 J 1/10W 0603 | R2_SA;HF_SA;G_SA; | Released | TA-I ; RALEC ; YAGEO ; WALSIN | RM06JTN0 ; RTT03000JTP ; RC0603JR-070RL ; WR06X000PTL | Multiple |  | Purchase | SMT | 7 | PCS | PR1 PR19 PR24 PR35 PR4 PR54 R486 |
| 2 | 55.B0707.S07G | 63.10134.1DL | CHIP RES 100 J 1/16W 0402 | R2_SA;HF_SA;G_SA; | Released | TA-I;RALEC;CYNTEC;YAGEO;WALSIN | RM04JTN101 ; RTT02101JTH ; RR0510S-101-JN ; RC0402JR-07100RL;WR04X101JTL | Multiple |  | Purchase | SMT | 2 | PCS | R358 R407 |
| 2 | 55.B0707.S07G | 63.2R037.18L | CHIP RES 2 J 1/2W 2010 | R2_SA;HF_SA;G_SA; | Released | TAI;RALEC | RM20JEN2R0;RTT202R0JTE | Multiple |  | Purchase | SMT | 34 | PCS | R100 R110 R121 R124 R134 R138 R151 R154 R161 R163 R175 R178 R190 R195 R205 R209 R218 R223 R234 R236 R245 R250 R260 R264 R273 R276 R289 R292 R302 R304 R542 R607 R608 R609 |
| 2 | 55.B0707.S07G | 63.47234.1DL | CHIP RES 4.7K J 1/16W 0402 | R2_SA;HF_SA;G_SA; | Released | TA-I;RALEC;CYNTEC;YAGEO;WALSIN | RM04JTN472 ; RTT02472JTH ; RR0510S-472-JN ; RC0402JR-074K7L;WR04X472JTL | Multiple |  | Purchase | SMT | 110 | PCS | R106 R108 R120 R123 R133 R136 R148 R150 R162 R165 R176 R180 R189 R193 R203 R204 R217 R221 R232 R235 R246 R248 R261 R262 R274 R278 R290 R291 R301 R306 R311 R317 R321 R322 R323 R324 R329 R332 R333 R336 R338 R339 R345 R349 R350 R367 R368 R371 R372 R381 R422 R423 R424 R425 R426 R427 R428 R429 R430 R431 R432 R433 R434 R435 R436 R437 R438 R439 R440 R441 R442 R443 R444 R445 R446 R447 R448 R449 R450 R451 R452 R453 R454 R455 R456 R457 R458 R459 R460 R461 R462 R463 R464 R465 R466 R467 R468 R469 R470 R471 R472 R473 R474 R475 R476 R477 R494 R495 R505 R506 |
| 2 | 55.B0707.S07G | 63.R0034.1DL | CHIP RES 0 J 1/16W 0402 | R2_SA;HF_SA;G_SA; | Released | TA-I;RALEC;CYNTEC;YAGEO;WALSIN | RM04JTN0;RTT02000JTH;RR0510X-000-XN;RC0402JR-070RL;WR04X000PTL | Multiple |  | Purchase | SMT | 132 | PCS | PR15 PR16 PR18 PR28 PR32 PR34 PR44 PR48 PR7 R103 R105 R112 R113 R116 R118 R126 R127 R130 R132 R140 R141 R144 R146 R153 R155 R158 R160 R168 R169 R172 R174 R182 R183 R186 R188 R196 R197 R200 R202 R210 R211 R214 R216 R224 R225 R228 R230 R238 R239 R242 R244 R252 R253 R256 R258 R266 R267 R270 R272 R280 R281 R284 R286 R294 R295 R298 R300 R308 R309 R310 R314 R318 R319 R326 R330 R334 R335 R343 R351 R352 R353 R354 R357 R360 R361 R365 R369 R373 R374 R376 R378 R379 R380 R382 R384 R386 R391 R392 R393 R394 R396 R398 R400 R402 R404 R408 R409 R410 R411 R412 R413 R414 R415 R416 R417 R418 R419 R420 R421 R480 R481 R507 R508 R509 R510 R511 R544 R545 R546 R547 R548 R549 |
| 2 | 55.B0707.S07G | 64.10015.6DL | CHIP RES 1K F 1/16W 0402 | R2_SA;HF_SA;G_SA; | Released | TA-I;RALEC;CYNTEC;YAGEO;WALSIN | RM04FTN1001 ; RTT021001FTH ; RR0510S-102-FN ; RC0402FR-071KL;WR04X1001FTL | Multiple |  | Purchase | SMT | 15 | PCS | R488 R489 R490 R491 R492 R493 R496 R497 R498 R499 R500 R501 R502 R503 R504 |
| 2 | 55.B0707.S07G | 64.10025.6DL | CHIP RES 10K F 1/16W 0402 | R2_SA;HF_SA;G_SA; | Released | TA-I;RALEC;CYNTEC;YAGEO;WALSIN | RM04FTN1002 ; RTT021002FTH ; RR0510S-103-FN ; RC0402FR-0710KL;WR04X1002FTL | Multiple |  | Purchase | SMT | 47 | PCS | PR2 PR23 PR25 PR39 PR41 PR49 PR5 PR50 PR51 R101 R114 R128 R142 R156 R170 R184 R198 R212 R226 R240 R254 R268 R282 R296 R342 R344 R356 R363 R366 R370 R375 R377 R383 R385 R387 R388 R390 R395 R397 R399 R401 R403 R405 R482 R483 R484 R485 |
| 2 | 55.B0707.S07G | 64.10026.6DL | CHIP RES 10K D 1/16W 0402 | R2_SA;HF_SA;G_SA; | Released | CYNTEC;RALEC;TA-I;WALSIN;YAGEO | RR0510Q-103-DN;RTT021002DTH;RM04DTN1002;WF04H1002DTL;RT0402DRE0710KL | Multiple |  | Purchase | SMT | 3 | PCS | PR14 PR27 PR43 |
| 2 | 55.B0707.S07G | 64.10035.6DL | CHIP RES 100K F 1/16W 0402 | R2_SA;HF_SA;G_SA; | Released | TA-I;RALEC;CYNTEC;YAGEO;WALSIN | RM04FTN1003 ; RTT021003FTH ; RR0510S-104-FN ; RC0402FR-07100KL;WR04X1003FTL | Multiple |  | Purchase | SMT | 4 | PCS | PR10 PR26 PR42 PR55 |
| 2 | 55.B0707.S07G | 64.10R05.6DL | CHIP RES 10 F 1/16W 0402 | R2_SA;HF_SA;G_SA; | Released | TA-I ; RALEC ; CYNTEC ; YAGEO | RM04FTN10R0 ; RTT0210R0FTH ; RR0510S-100-FN ; RC0402FR-0710RL | Multiple |  | Purchase | SMT | 3 | PCS | PR21 PR37 PR6 |
| 2 | 55.B0707.S07G | 64.11535.6DL | CHIP RES 115K F 1/16W 0402 | R2_SA;HF_SA;G_SA; | Released | YAGEO;CYNTEC;TAI;RALEC;WALSIN | RC0402FR-07115KL;RR0510S-1153-FN;RM04FTN1153;RTT021153FTH ;WR04X1153FTL | Multiple |  | Purchase | SMT | 3 | PCS | PR13 PR30 PR46 |
| 2 | 55.B0707.S07G | 64.20015.6DL | CHIP RES 2K F 1/16W 0402 | R2_SA;HF_SA;G_SA; | Released | TA-I;RALEC;CYNTEC;YAGEO;WALSIN | RM04FTN2001 ; RTT022001FTH ; RR0510S-202-FN ; RC0402FR-072KL;WR04X2001FTL | Multiple |  | Purchase | SMT | 1 | PCS | R389 |
| 2 | 55.B0707.S07G | 64.20035.6DL | CHIP RES 200K F 1/16W 0402 | R2_SA;HF_SA;G_SA; | Released | TA-I;RALEC;CYNTEC;YAGEO;WALSIN | RM04FTN2003 ; RTT022003FTH ; RR0510S-204-FN ; RC0402FR-07200KL;WR04X2003FTL | Multiple |  | Purchase | SMT | 30 | PCS | R109 R122 R137 R149 R166 R181 R194 R207 R222 R233 R249 R263 R275 R288 R307 R478 R479 R550 R551 R552 R553 R554 R555 R556 R557 R558 R559 R560 R561 R562 |
| 2 | 55.B0707.S07G | 64.20045.6DL | CHIP RES 2M F 1/16W 0402 | R2_SA;HF_SA;G_SA; | Released | TA-I;RALEC;CYNTEC;YAGEO | RM04FTN2004;RTT022004FTH;RR0510S-2004-FN;RC0402FR-072ML | Multiple |  | Purchase | SMT | 1 | PCS | PR52 |
| 2 | 55.B0707.S07G | 64.22005.55L | CHIP RES 220 F 1/10W 0603 | R2_SA;HF_SA;G_SA; | Released | TA-I ; RALEC ; YAGEO | RM06FTN2200 ; RTT032200FTP ; RC0603FR-07220RL | Multiple |  | Purchase | SMT | 15 | PCS | R111 R125 R139 R152 R167 R177 R191 R208 R219 R237 R251 R265 R279 R293 R303 |
| 2 | 55.B0707.S07G | 64.22125.55L | CHIP RES 22.1K F 1/10W 0603 | R2_SA;HF_SA;G_SA; | Released | TA-I ; RALEC ; YAGEO | RM06FTN2212 ; RTT032212FTP ; RC0603FR-0722K1L | Multiple |  | Purchase | SMT | 1 | PCS | PR56 |
| 2 | 55.B0707.S07G | 64.24915.6DL | CHIP RES 2.49K F 1/16W 0402 | R2_SA;HF_SA;G_SA; | Released | TA-I;RALEC;CYNTEC;YAGEO;WALSIN | RM04FTN2491;RTT022491FTH;RR0510S-2491-FN;RC0402FR-072K49L;WR04X2491FTL | Multiple |  | Purchase | SMT | 3 | PCS | PR17 PR3 R487 |
| 2 | 55.B0707.S07G | 64.30035.6DL | CHIP RES 300K F 1/16W 0402 | R2_SA;HF_SA;G_SA; | Released | TA-I;RALEC;CYNTEC;YAGEO;WALSIN | RM04FTN3003;RTT023003FTH;RR0510S-304-FN;RC0402FR-07300KL;WR04X3003FTL | Multiple |  | Purchase | SMT | 15 | PCS | R563 R564 R565 R566 R567 R568 R569 R570 R571 R572 R573 R574 R575 R576 R577 |
| 2 | 55.B0707.S07G | 64.33005.6DL | CHIP RES 330 F 1/16W 0402 | R2_SA;HF_SA;G_SA; | Released | CYNTEC;RALEC;TAI;YAGEO | RR0510S-331-FN;RTT023300FTH;RM04FTN3300;RC0402FR-07330RL | Multiple |  | Purchase | SMT | 15 | PCS | R104 R117 R131 R145 R159 R173 R187 R201 R215 R229 R243 R257 R271 R285 R299 |
| 2 | 55.B0707.S07G | 64.40205.6DL | CHIP RES 402 F 1/16W 0402 | R2_SA;HF_SA;G_SA; | Released | TA-I;RALEC;CYNTEC;YAGEO | RM04FTN4020;RTT024020FTH;RR0510S-4020-FN;RC0402FR-07402RL | Multiple |  | Purchase | SMT | 15 | PCS | R102 R115 R129 R143 R157 R171 R185 R199 R213 R227 R241 R255 R269 R283 R297 |
| 2 | 55.B0707.S07G | 64.47035.6DL | CHIP RES 470K F 1/16W 0402 | R2_SA;HF_SA;G_SA; | Released | TA-I;RALEC;CYNTEC;YAGEO;WALSIN | RM04FTN4703;RTT024703FTH;RR0510S-474-FN;RC0402FR-07470KL;WR04X4703FTL | Multiple |  | Purchase | SMT | 1 | PCS | PR53 |
| 2 | 55.B0707.S07G | 64.73225.6DL | CHIP RES 73.2K F 1/16W 0402 | R2_SA;HF_SA;G_SA; | Released | TA-I;RALEC;CYNTEC;YAGEO;WALSIN | RM04FTN7322;RTT027322FTH;RR0510S-7322-FN;RC0402FR-0773K2L;WR04X7322FTL | Multiple |  | Purchase | SMT | 3 | PCS | PR11 PR29 PR45 |
| 2 | 55.B0707.S07G | 68.00084.771 | CHIP BEAD BLM41PG600SN1L MURAT | R2_SA; | Released | MURATA | BLM41PG600SN1L | Single |  | Purchase | SMT | 3 | PCS | PL1 PL3 PL5 |
| 2 | 55.B0707.S07G | 68.2201D.10J | CHIP IND 22UH #A921CY-220M=P3 | R2_SA; | Released | TOKO | #A921CY-220M=P3 | Single |  | Purchase | SMT | 1 | PCS | PL7 |
| 2 | 55.B0707.S07G | 68.4R71A.20Q | CHIP CHOKE 4.7UH M PCMB104T-4R7MS | R2_SA; | Released | CYNTEC | PCMB104T-4R7MS | Single |  | Purchase | SMT | 3 | PCS | PL2 PL4 PL6 |
| 2 | 55.B0707.S07G | 72.02464.00Q | IC EPROM 24LC64T-I/STG TSSOP8P | R2_SA; | Released | MICROCHIP | 24LC64T-I/STG | Single |  | Purchase | SMT | 1 | PCS | U50 |
| 2 | 55.B0707.S07G | 73.01G08.L03 | IC CMOS SN74LVC1G08DCKR SC-70 | R2_SA;HF_SA;G_SA; | Released | TI | SN74LVC1G08DCKR | Single |  | Purchase | SMT | 30 | PCS | U1 U10 U12 U13 U15 U16 U18 U19 U21 U22 U24 U25 U27 U28 U3 U30 U31 U33 U34 U36 U37 U39 U4 U40 U42 U43 U45 U6 U7 U9 |
| 2 | 55.B0707.S07G | 74.00075.B79 | IC TEMP SENSOR TMP75AIDGKR MSOP 8P | R2_SA; | Released | TI | TMP75AIDGKR | Single |  | Purchase | SMT | 4 | PCS | U46 U47 U48 U49 |
| 2 | 55.B0707.S07G | 74.01015.049 | IC CONV ADS1015IDGSR MSOP 10P | R2_SA; | Released | TI | ADS1015IDGSR | Single |  | Purchase | SMT | 1 | PCS | U53 |
| 2 | 55.B0707.S07G | 74.08201.04P | IC DC/DC REGULATOR SY8201ABC SOT23-6 | R2_SA;HF_SA; | Released | SILERGY | SY8201ABC | Single |  | Purchase | SMT | 1 | PCS | U54 |
| 2 | 55.B0707.S07G | 74.53319.073 | IC PWR CTRL TPS53319DQPR QFN 22P | R2_SA;HF_SA; | Released | TI | TPS53319DQPR | Single |  | Purchase | SMT | 3 | PCS | PU1 PU2 PU3 |
| 2 | 55.B0707.S07G | 77.21561.00L | CHIP CAP POS 15U 25V 25TQC15M | R2_SA;HF_SA;G_SA; | Released | SANYO | 25TQC15M | Single |  | Purchase | SMT | 2 | PCS | TC1 TC2 |
| 2 | 55.B0707.S07G | 77.23371.061 | CHIP CAP POS 330U 10V D4 10TPB | R2_SA;HF_SA; | Released | SANYO | 10TPB330M | Single |  | Purchase | SMT | 6 | PCS | PTC1 PTC2 PTC3 PTC4 PTC5 PTC6 |
| 2 | 55.B0707.S07G | 78.10324.2FL | CHIP CAP C 0.01U 50V K0402 X7R | R2_SA;HF_SA;G_SA; | Released | MURATA;PHYCOMP;DARFON;TDK;SAMSUNG;WALSIN;MURATA | GRM155R71H103KA88D;223858715636;C1005X7R103KGT;C1005X7R1H103KT;CL05B103KB5NNNC;0402B103K500CT;WBM155R71H103KA01D | Multiple |  | Purchase | SMT | 75 | PCS | C100 C103 C104 C105 C108 C118 C119 C120 C121 C131 C134 C135 C136 C137 C147 C150 C151 C152 C153 C156 C166 C167 C168 C169 C178 C182 C183 C184 C185 C190 C198 C199 C200 C201 C204 C214 C215 C216 C217 C222 C230 C231 C232 C233 C238 C246 C247 C248 C249 C254 C262 C263 C264 C265 C270 C278 C279 C280 C281 C286 C294 C295 C296 C297 C303 C310 C311 C312 C313 C323 C326 C327 C328 C329 C332 |
| 2 | 55.B0707.S07G | 78.10421.2FL | CHIP CAP C 0.1U 16V K0402 X7R | R2_SA;HF_SA;G_SA; | Released | DARFON;MURATA;PHYCOMP;SAMSUNG;TAIYO;TDK;WALSIN;YAGEO | C1005X7R104KET;GRM155R71C104KA88D;223878715649;CL05B104KO5NNNC;EMK105BJ104KV-FR ;C1005X7R1C104KT000F;0402B104K160CT;CC0402KRX7R7BB104 | Multiple |  | Purchase | SMT | 6 | PCS | C352 C353 C354 C361 C362 PC41 |
| 2 | 55.B0707.S07G | 78.10422.2BL | CHIP CAP C 0.1U 25V K0603 X7R | R2_SA;HF_SA;G_SA; | Released | AVX;DARFON;MURATA;PHYCOMP;SAMSUNG;TAIYO;TDK;WALSIN;YAGEO | 06033C104KAT2A;C1608X7R104KFT;GRM188R71E104KA01D;223891615649;CL10B104KA8NNNC;TMK107BJ104KA-T;C1608X7R1E104KT;0603B104K250CT;CC0603KRX7R8BB104 | Multiple |  | Purchase | SMT | 1 | PCS | PC44 |
| 2 | 55.B0707.S07G | 78.10422.5FL | CHIP CAP C 0.1U 25V K0402 X5R | R2_SA;HF_SA;G_SA; | Released | MURATA;YAGEO;TDK;TAIYO;SAMSUNG;WALSIN;DARFON | GRM155R61E104KA87D;CC0402KRX5R8BB104;C1005X5R1E104KT000E;TMK105BJ104KV-F;CL05A104KA5NNNC;0402X104K250CT;C1005X5R104KFT | Multiple |  | Purchase | SMT | 6 | PCS | PC15 PC21 PC28 PC34 PC7 PC8 |
| 2 | 55.B0707.S07G | 78.10423.2FL | CHIP CAP C 0.1U 10V K0402 X7R | R2_SA;HF_SA;G_SA; | Released | MURATA;PHYCOMP;SAMSUNG;TAIYO;TDK;DARFON;WALSIN;MURATA;YAGEO | GRM155R71A104KA01D;223824715649;CL05B104KP5NNNC;RMLMK105BJ104KV-F;C1005X7R1A104KT000F;C1005X7R104KDT;0402B104K100CT;WBM155R71A104KA01D;CC0402KRX7R6BB104 | Multiple |  | Purchase | SMT | 34 | PCS | C102 C110 C117 C125 C133 C141 C149 C158 C165 C171 C181 C187 C197 C203 C213 C219 C229 C235 C245 C253 C261 C269 C277 C283 C293 C301 C309 C315 C324 C339 C340 C341 C342 C343 |
| 2 | 55.B0707.S07G | 78.10424.2BL | CHIP CAP C 0.1U 50V K0603 X7R | R2_SA;HF_SA;G_SA; | Released | MURATA;TDK;AVX;PHYCOMP;SAMSUNG;DARFON;MATSUKI;WALSIN | GRM188R71H104KA93D;C1608X7R1H104KT000N;06035C104KAT2A;223858615649;CL10B104KB8NNNC;C1608X7R104KGT;MAG03X7R1H104K;0603B104K500CT | Multiple |  | Purchase | SMT | 1 | PCS | C347 |
| 2 | 55.B0707.S07G | 78.10521.2BL | CHIP CAP C 1U 16V K0603 X7R | R2_SA;HF_SA;G_SA; | Released | KEMET;MURATA;TAIYO;TDK;PHYCOMP;WALSIN;SAMSUNG;DARFON | C0603C105K4RAC;GRM188R71C105KA12D;EMK107B7105KA-T;C1608X7R1C105KT;223878615663;0603B105K160CT;CL10B105KO8NNNC;C1608X7R105KET | Multiple |  | Purchase | SMT | 16 | PCS | C106 C122 C138 C154 C172 C188 C205 C220 C236 C250 C266 C284 C298 C316 C330 C346 |
| 2 | 55.B0707.S07G | 78.10522.5BL | CHIP CAP C 1U 25V K0603 X5R | R2_SA;HF_SA;G_SA; | Released | MURATA;TDK;PHYCOMP;TAIYO;MATSUKI;DARFON;TDK;WALSIN;SAMSUNG;YAGEO | GRM188R61E105KA12D;C1608X5R1E105KT000N;223891613663;TMK107BJ105KA-T;MAG03X5R1E105K;C1608X5R105KFT;C1608X5R1E105KT000N;0603X105K250CT;CL10A105KA8NNNC;CC0603KRX5R8BB105 | Multiple |  | Purchase | SMT | 19 | PCS | C115 C124 C130 C132 C146 C148 C157 C163 C179 C195 C211 C227 C243 C259 C272 C291 C307 C322 C338 |
| 2 | 55.B0707.S07G | 78.10523.5FL | CHIP CAP C 1U 10V K0402 X5R | R2_SA;HF_SA;G_SA; | Released | MURATA;TDK;DARFON;MATSUKI;PHYCOMP;TAIYO;SAMSUNG;WALSIN | GRM155R61A105KE15D;C1005X5R1A105KT;C1005X5R105KDT;MAG02X5R1A105K;223824713663;LMK105BJ105KVF;CL05A105KP5NNNC;0402X105K100CT | Multiple |  | Purchase | SMT | 4 | PCS | C363 PC10 PC17 PC30 |
| 2 | 55.B0707.S07G | 78.10621.22L | CHIP CAP C 10U 16V K1206 X7R | R2_SA;HF_SA;G_SA; | Released | MURATA;TDK;AVX;DARFON;SAMSUNG;TAIYO | GRM31CR71C106KA12L;C3216X7R1C106KT;CM316X7R106K16AT;C3216X7R106KEP;CL31B106KOHNNNE;EMK316B7106KL-T | Multiple |  | Purchase | SMT | 21 | PCS | C107 C123 C139 C155 C173 C189 C206 C221 C237 C251 C267 C285 C299 C317 C331 PC11 PC12 PC25 PC26 PC38 PC39 |
| 2 | 55.B0707.S07G | 78.10622.51L | CHIP CAP C 10U 25V K0805 X5R | R2_SA;HF_SA;G_SA; | Released | MATSUKI;SAMSUNG;TAIYO;AVX;MURATA;TDK;YAGEO | MAG05X5R1E106K;CL21A106KAYNNNE;TMK212BJ106KG-TD;CM21X5R106K25AT;GRM21BR61E106KA73L;C2012X5R1E106KT;CC0805KKX5R8BB106 | Multiple |  | Purchase | SMT | 2 | PCS | C350 C351 |
| 2 | 55.B0707.S07G | 78.10622.52L | CHIP CAP C 10U 25V K1206 X5R | R2_SA;HF_SA;G_SA; | Released | TAIYO;MURATA;AVX;TDK;KEMET;MATSUKI;PHYCOMP;DARFON;SAMSUNG | TMK316BJ106KL-T;GRM31CR61E106KA12L;12063D106KAT2A;C3216X5R1E106KT;C1206C106K3PAC;MAG06X5R1E106K;222291113676;C3216X5R106KFP;CL31A106KAHNNNE | Multiple |  | Purchase | SMT | 62 | PCS | C111 C112 C113 C114 C126 C127 C128 C129 C142 C143 C144 C145 C159 C160 C161 C162 C174 C175 C176 C177 C191 C192 C193 C194 C207 C208 C209 C210 C223 C224 C225 C226 C239 C240 C241 C242 C255 C256 C257 C258 C271 C273 C274 C275 C287 C288 C289 C290 C302 C304 C305 C306 C318 C319 C320 C321 C333 C334 C335 C336 C348 C349 |
| 2 | 55.B0707.S07G | 78.22034.1BL | CHIP CAP 22P50V J0603 NPO(ROHS | R2_SA;HF_SA;G_SA; | Released | PHYCOMP;MURATA;AVX;TDK;SAMSUNG;DARFON;WALSIN | 223886715229;GRM1885C1H220JA01D;06035A220JAT2A;C1608C0G1H220JT;CL10C220JB8NNNC;C1608NPO220JGT;0603N220J500LT | Multiple |  | Purchase | SMT | 1 | PCS | PC42 |
| 2 | 55.B0707.S07G | 78.22611.52L | CHIP CAP 22U 16V M1206 X5R | R2_SA;HF_SA;G_SA; | Released | MURATA;TAIYO;AVX;SAMSUNG | GRM31CR61C226ME15L;EMK316BJ226ML-T;CM316X5R226M16AT;CL31A226KOHNNNE | Multiple |  | Purchase | SMT | 1 | PCS | PC43 |
| 2 | 55.B0707.S07G | 78.22612.51L | CHIP CAP C 22U 25V M0805 X5R | R2_SA;HF_SA;G_SA; | Released | MURATA;SANSUNG;DARFON;TDK | GRM21BR61E226ME44L;CL21A226MAQNNNE;C2012X5R226MFP;C2012X5R1E226MT | Multiple |  | Purchase | SMT | 19 | PCS | PC1 PC14 PC16 PC18 PC2 PC22 PC24 PC27 PC29 PC3 PC31 PC35 PC37 PC4 PC46 PC47 PC5 PC68 PC69 |
| 2 | 55.B0707.S07G | 78.33322.2FL | CHIP CAP C 0.033U 25V K0402 X7 | R2_SA;HF_SA;G_SA; | Released | MURATA ; TDK ; KEMET; WALSIN | GRM155R71E333KA88D ; C1005X7R1E333KT000F ; C0402C333K3RACTU; 0402B333K250CT | Multiple |  | Purchase | SMT | 30 | PCS | C364 C365 C366 C367 C368 C369 C370 C371 C372 C373 C374 C375 C376 C377 C378 C379 C380 C381 C382 C383 C384 C385 C386 C387 C388 C389 C390 C391 C392 C393 |
| 2 | 55.B0707.S07G | 78.47522.51L | CHIP CAP C 4.7U 25V K0805 X5R | R2_SA;HF_SA;G_SA; | Released | MURATA;AVX;TAIYO;MATSUKI;TDK;SAMSUNG;PHYCOMP | GRM21BR61E475KA12L;CM21X5R475K25AT;TMK212BJ475KG-T;MAG05X5R1E475K;C2012X5R1E475KT50HN;CL21A475KAQNNNE;222291013672 | Multiple |  | Purchase | SMT | 3 | PCS | PC23 PC36 PC6 |
| 2 | 55.B0707.S07G | 78.47524.L2L | CHIP CAP C 4.7UF 50V K1206 X5R T=0.9 | R2_SA;HF_SA;G_SA; | Released | MURATA;SAMSUNG;TAIYO | GRM319R61H475KA12D;CL31A475KB9LNNC;UMK316BJ475KD-T | Multiple |  | Purchase | SMT | 1 | PCS | PC40 |
| 2 | 55.B0707.S07G | 78.68124.2FL | CHIP CAP C 680P 50V K0402 X7R | R2_SA;HF_SA;G_SA; | Released | AVX;DARFON;MURATA;PHYCOMP;TAIYO;TDK;WALSIN | CM05X7R681K50AT;C1005X7R681KGT;GRM155R71H681KA01D;223858715621;UMK105BJ681KV-F;C1005X7R1H681KT;0402B681K500CT | Multiple |  | Purchase | SMT | 3 | PCS | PC13 PC19 PC32 |
| 2 | 55.B0707.S07G | 83.19226.C70 | LED R/B 19-226/R6BHC-B01/2T SM | R2_SA; | Released | EVERLIGHT | 19-226/R6BHC-B01/2T | Single |  | Purchase | SMT | 15 | PCS | LED1 LED10 LED11 LED12 LED13 LED14 LED15 LED2 LED3 LED4 LED5 LED6 LED7 LED8 LED9 |
| 2 | 55.B0707.S07G | 84.02003.A37 | FET MOS P2003EVG PC SO-8 | R2_SA;HF_SA; | Released | NIKO | P2003EVG | Single |  | Purchase | SMT | 15 | PCS | U11 U14 U17 U2 U20 U23 U26 U29 U32 U35 U38 U41 U44 U5 U8 |
| 2 | 55.B0707.S07G | 84.03904.L06 | XTOR PMBS3904 NPN SOT23 (GP) | R2_SA;HF_SA;G_SA; | Released | NXP | PMBS3904 | Single |  | Purchase | SMT | 15 | PCS | Q34 Q35 Q36 Q37 Q38 Q39 Q40 Q41 Q42 Q43 Q44 Q45 Q46 Q47 Q48 |
| 2 | 55.B0707.S07G | 84.04406.B37 | FET MOS AO4406AL NC SO-8(HF) | R2_SA;HF_SA;G_SA; | Released | AOS | AO4406AL | Single |  | Purchase | SMT | 15 | PCS | Q11 Q13 Q15 Q17 Q19 Q2 Q21 Q23 Q25 Q27 Q29 Q3 Q5 Q7 Q9 |
| 2 | 55.B0707.S07G | 84.27002.C3F | FET MOS 2N7002DW-7-F NC SOT363 | R2_SA;HF_SA; | Released | DIODES | 2N7002DW-7-F | Single |  | Purchase | SMT | 30 | PCS | Q1 Q10 Q12 Q14 Q16 Q18 Q20 Q22 Q24 Q26 Q28 Q30 Q31 Q32 Q33 Q4 Q52 Q54 Q56 Q58 Q6 Q60 Q62 Q64 Q66 Q68 Q70 Q72 Q74 Q8 |
| 2 | 55.B0707.S07G | 84.27002.W31 | FET MOS 2N7002 NC SOT-23 | R2_SA;HF_SA;G_SA; | Released | PANJIT | 2N7002 | Single |  | Purchase | SMT | 15 | PCS | Q49 Q50 Q51 Q53 Q55 Q57 Q59 Q61 Q63 Q65 Q67 Q69 Q71 Q73 Q75 |
